# SCM (Grand Teton) — schematic netlist excerpt (pin names and nets, part order shuffled) for the footprints in the layout excerpt that follows; sources: Cadence DE-HDL packaged netlist, KiCad conversion of 12092022_DA0F0TMDCD0_F0T_Management_Board_D_brd_V3_OCP.brd

PC217  Q_CAP  22UF 10V 20% X6S  pkg C0805  page 51 : A = P5V_AUX ; B = GND
R383  Q_RES  10K 1% CHIP  pkg 0402LF  page 28 : A = P3V3_AUX ; B = USB_OC0_REAR_N
C37  Q_CAP  0.1UF 25V 10% X7R  pkg 0402  page 15 : A = P3V3_RGM ; B = GND

(kicad_pcb
	(version 20260206)
	(generator "pcbnew")
	(generator_version "10.0")
	(general
		(thickness 1.6)
		(legacy_teardrops no)
	)
	(paper "A4")
	(title_block
		(title "12092022_DA0F0TMDCD0_F0T_Management_Board_D_brd_V3_OCP.brd")
		(comment 1 "Grand Teton / footprints 70-72 of 1440")
	)
	(layers
		(0 "F.Cu" signal "TOP")
		(4 "In1.Cu" signal "GND")
		(6 "In2.Cu" signal "IN1")
		(8 "In3.Cu" signal "GND1")
		(10 "In4.Cu" signal "IN2")
		(12 "In5.Cu" signal "VCC")
		(14 "In6.Cu" signal "VCC1")
		(16 "In7.Cu" signal "IN3")
		(18 "In8.Cu" signal "GND2")
		(20 "In9.Cu" signal "IN4")
		(22 "In10.Cu" signal "GND3")
		(2 "B.Cu" signal "BOTTOM")
		(9 "F.Adhes" user "F.Adhesive")
		(11 "B.Adhes" user "B.Adhesive")
		(13 "F.Paste" user "Package Geometry/Pastemask Top")
		(15 "B.Paste" user "Package Geometry/Pastemask Bottom")
		(5 "F.SilkS" user "Ref Des/Silkscreen Top")
		(7 "B.SilkS" user "Ref Des/Silkscreen Bottom")
		(1 "F.Mask" user "Board Geometry/Soldermask Top")
		(3 "B.Mask" user "Board Geometry/Soldermask Bottom")
		(17 "Dwgs.User" user "User.Drawings")
		(19 "Cmts.User" user "User.Comments")
		(21 "Eco1.User" user "User.Eco1")
		(23 "Eco2.User" user "User.Eco2")
		(25 "Edge.Cuts" user "Board Geometry/Outline")
		(27 "Margin" user)
		(31 "F.CrtYd" user "Package Geometry/Place Bound Top")
		(29 "B.CrtYd" user "Package Geometry/Place Bound Bottom")
		(35 "F.Fab" user "Ref Des/Assembly Top")
		(33 "B.Fab" user "Ref Des/Assembly Bottom")
	)
	(footprint ""
		(layer "F.Cu")
		(at 11.43 -31.837122 -90)
		(property "Reference" "PC217"
			(at 0 0 270)
			(layer "F.SilkS")
			(hide yes)
			(effects
				(font
					(size 1.27 1.27)
				)
			)
		)
		(property "Value" ""
			(at 0 0 270)
			(layer "F.Fab")
			(effects
				(font
					(size 1.27 1.27)
				)
			)
		)
		(duplicate_pad_numbers_are_jumpers no)
		(fp_line
			(start -1.651 0.8382)
			(end -1.651 -0.8382)
			(stroke
				(width 0.1524)
				(type default)
			)
			(layer "F.SilkS")
		)
		(fp_line
			(start 0 0.8382)
			(end 0 -0.8382)
			(stroke
				(width 0.1524)
				(type default)
			)
			(layer "F.SilkS")
		)
		(fp_line
			(start 1.651 0.8382)
			(end -1.651 0.8382)
			(stroke
				(width 0.1524)
				(type default)
			)
			(layer "F.SilkS")
		)
		(fp_line
			(start -1.651 -0.8382)
			(end 1.651 -0.8382)
			(stroke
				(width 0.1524)
				(type default)
			)
			(layer "F.SilkS")
		)
		(fp_line
			(start 1.651 -0.8382)
			(end 1.651 0.8382)
			(stroke
				(width 0.1524)
				(type default)
			)
			(layer "F.SilkS")
		)
		(fp_line
			(start -1.55956 0.7366)
			(end -1.524 0.7366)
			(stroke
				(width 0.1)
				(type default)
			)
			(layer "F.Fab")
		)
		(fp_line
			(start -1.524 0.7366)
			(end 1.524 0.7366)
			(stroke
				(width 0.1)
				(type default)
			)
			(layer "F.Fab")
		)
		(fp_line
			(start 1.524 0.7366)
			(end 1.55956 0.7366)
			(stroke
				(width 0.1)
				(type default)
			)
			(layer "F.Fab")
		)
		(fp_line
			(start 1.55956 0.7366)
			(end 1.55956 -0.7366)
			(stroke
				(width 0.1)
				(type default)
			)
			(layer "F.Fab")
		)
		(fp_line
			(start -1.55956 -0.7366)
			(end -1.55956 0.7366)
			(stroke
				(width 0.1)
				(type default)
			)
			(layer "F.Fab")
		)
		(fp_line
			(start -1.524 -0.7366)
			(end -1.55956 -0.7366)
			(stroke
				(width 0.1)
				(type default)
			)
			(layer "F.Fab")
		)
		(fp_line
			(start 1.524 -0.7366)
			(end -1.524 -0.7366)
			(stroke
				(width 0.1)
				(type default)
			)
			(layer "F.Fab")
		)
		(fp_line
			(start 1.55956 -0.7366)
			(end 1.524 -0.7366)
			(stroke
				(width 0.1)
				(type default)
			)
			(layer "F.Fab")
		)
		(pad "1" smd rect
			(at -0.94996 0 90)
			(size 1.1176 1.3716)
			(layers "F.Cu" "F.Mask" "F.Paste")
			(net "P5V_AUX")
		)
		(pad "2" smd rect
			(at 0.94996 0 90)
			(size 1.1176 1.3716)
			(layers "F.Cu" "F.Mask" "F.Paste")
			(net "GND")
		)
	)
	(footprint ""
		(layer "F.Cu")
		(at 46.863 -24.384)
		(property "Reference" "R383"
			(at 0 0 0)
			(layer "F.SilkS")
			(hide yes)
			(effects
				(font
					(size 1.27 1.27)
				)
			)
		)
		(property "Value" ""
			(at 0 0 0)
			(layer "F.Fab")
			(effects
				(font
					(size 1.27 1.27)
				)
			)
		)
		(duplicate_pad_numbers_are_jumpers no)
		(fp_line
			(start -0.7874 -0.4064)
			(end 0.7874 -0.4064)
			(stroke
				(width 0.1524)
				(type default)
			)
			(layer "F.SilkS")
		)
		(fp_line
			(start -0.7874 0.4064)
			(end -0.7874 -0.4064)
			(stroke
				(width 0.1524)
				(type default)
			)
			(layer "F.SilkS")
		)
		(fp_line
			(start 0.7874 -0.4064)
			(end 0.7874 0.4064)
			(stroke
				(width 0.1524)
				(type default)
			)
			(layer "F.SilkS")
		)
		(fp_line
			(start 0.7874 0.4064)
			(end -0.7874 0.4064)
			(stroke
				(width 0.1524)
				(type default)
			)
			(layer "F.SilkS")
		)
		(fp_line
			(start -0.67945 -0.305054)
			(end -0.12065 -0.305054)
			(stroke
				(width 0.1)
				(type default)
			)
			(layer "F.Fab")
		)
		(fp_line
			(start -0.67945 0.3048)
			(end -0.67945 -0.305054)
			(stroke
				(width 0.1)
				(type default)
			)
			(layer "F.Fab")
		)
		(fp_line
			(start -0.12065 -0.305054)
			(end -0.12065 -0.2794)
			(stroke
				(width 0.1)
				(type default)
			)
			(layer "F.Fab")
		)
		(fp_line
			(start -0.12065 -0.2794)
			(end 0.12065 -0.2794)
			(stroke
				(width 0.1)
				(type default)
			)
			(layer "F.Fab")
		)
		(fp_line
			(start -0.12065 0.2794)
			(end -0.12065 0.3048)
			(stroke
				(width 0.1)
				(type default)
			)
			(layer "F.Fab")
		)
		(fp_line
			(start -0.12065 0.3048)
			(end -0.67945 0.3048)
			(stroke
				(width 0.1)
				(type default)
			)
			(layer "F.Fab")
		)
		(fp_line
			(start 0.120396 0.2794)
			(end -0.12065 0.2794)
			(stroke
				(width 0.1)
				(type default)
			)
			(layer "F.Fab")
		)
		(fp_line
			(start 0.120396 0.3048)
			(end 0.120396 0.2794)
			(stroke
				(width 0.1)
				(type default)
			)
			(layer "F.Fab")
		)
		(fp_line
			(start 0.12065 -0.3048)
			(end 0.67945 -0.3048)
			(stroke
				(width 0.1)
				(type default)
			)
			(layer "F.Fab")
		)
		(fp_line
			(start 0.12065 -0.2794)
			(end 0.12065 -0.3048)
			(stroke
				(width 0.1)
				(type default)
			)
			(layer "F.Fab")
		)
		(fp_line
			(start 0.67945 -0.3048)
			(end 0.67945 0.3048)
			(stroke
				(width 0.1)
				(type default)
			)
			(layer "F.Fab")
		)
		(fp_line
			(start 0.67945 0.3048)
			(end 0.120396 0.3048)
			(stroke
				(width 0.1)
				(type default)
			)
			(layer "F.Fab")
		)
		(pad "1" smd circle
			(at -0.40005 0)
			(size 0 0)
			(layers "F.Cu" "F.Mask" "F.Paste")
			(net "P3V3_AUX")
		)
		(pad "2" smd circle
			(at 0.40005 0)
			(size 0 0)
			(layers "F.Cu" "F.Mask" "F.Paste")
			(net "USB_OC0_REAR_N")
		)
	)
	(footprint ""
		(layer "F.Cu")
		(at 53.537612 -28.027376 -90)
		(property "Reference" "C37"
			(at 0 0 270)
			(layer "F.SilkS")
			(hide yes)
			(effects
				(font
					(size 1.27 1.27)
				)
			)
		)
		(property "Value" ""
			(at 0 0 270)
			(layer "F.Fab")
			(effects
				(font
					(size 1.27 1.27)
				)
			)
		)
		(duplicate_pad_numbers_are_jumpers no)
		(fp_line
			(start -0.7874 0.4064)
			(end -0.7874 -0.4064)
			(stroke
				(width 0.1524)
				(type default)
			)
			(layer "F.SilkS")
		)
		(fp_line
			(start 0.7874 0.4064)
			(end -0.7874 0.4064)
			(stroke
				(width 0.1524)
				(type default)
			)
			(layer "F.SilkS")
		)
		(fp_line
			(start -0.7874 -0.4064)
			(end 0.7874 -0.4064)
			(stroke
				(width 0.1524)
				(type default)
			)
			(layer "F.SilkS")
		)
		(fp_line
			(start 0.7874 -0.4064)
			(end 0.7874 0.4064)
			(stroke
				(width 0.1524)
				(type default)
			)
			(layer "F.SilkS")
		)
		(fp_line
			(start -0.67945 0.3048)
			(end -0.67945 -0.305054)
			(stroke
				(width 0.1)
				(type default)
			)
			(layer "F.Fab")
		)
		(fp_line
			(start -0.12065 0.3048)
			(end -0.67945 0.3048)
			(stroke
				(width 0.1)
				(type default)
			)
			(layer "F.Fab")
		)
		(fp_line
			(start 0.120396 0.3048)
			(end 0.120396 0.2794)
			(stroke
				(width 0.1)
				(type default)
			)
			(layer "F.Fab")
		)
		(fp_line
			(start 0.67945 0.3048)
			(end 0.120396 0.3048)
			(stroke
				(width 0.1)
				(type default)
			)
			(layer "F.Fab")
		)
		(fp_line
			(start -0.12065 0.2794)
			(end -0.12065 0.3048)
			(stroke
				(width 0.1)
				(type default)
			)
			(layer "F.Fab")
		)
		(fp_line
			(start 0.120396 0.2794)
			(end -0.12065 0.2794)
			(stroke
				(width 0.1)
				(type default)
			)
			(layer "F.Fab")
		)
		(fp_line
			(start -0.12065 -0.2794)
			(end 0.12065 -0.2794)
			(stroke
				(width 0.1)
				(type default)
			)
			(layer "F.Fab")
		)
		(fp_line
			(start 0.12065 -0.2794)
			(end 0.12065 -0.3048)
			(stroke
				(width 0.1)
				(type default)
			)
			(layer "F.Fab")
		)
		(fp_line
			(start 0.12065 -0.3048)
			(end 0.67945 -0.3048)
			(stroke
				(width 0.1)
				(type default)
			)
			(layer "F.Fab")
		)
		(fp_line
			(start 0.67945 -0.3048)
			(end 0.67945 0.3048)
			(stroke
				(width 0.1)
				(type default)
			)
			(layer "F.Fab")
		)
		(fp_line
			(start -0.67945 -0.305054)
			(end -0.12065 -0.305054)
			(stroke
				(width 0.1)
				(type default)
			)
			(layer "F.Fab")
		)
		(fp_line
			(start -0.12065 -0.305054)
			(end -0.12065 -0.2794)
			(stroke
				(width 0.1)
				(type default)
			)
			(layer "F.Fab")
		)
		(pad "1" smd circle
			(at -0.40005 0 270)
			(size 0 0)
			(layers "F.Cu" "F.Mask" "F.Paste")
			(net "P3V3_RGM")
		)
		(pad "2" smd circle
			(at 0.40005 0 270)
			(size 0 0)
			(layers "F.Cu" "F.Mask" "F.Paste")
			(net "GND")
		)
	)
)
